(kicad_pcb
	(version 20260206)
	(generator "pcbnew")
	(generator_version "10.0")
	(general
		(thickness 1.6)
		(legacy_teardrops no)
	)
	(paper "A4")
	(title_block
		(title "Bryce Canyon_F.DPB_16315-1-OCP.brd")
		(comment 1 "Bryce Canyon / footprints 1385-1390 of 2223")
	)
	(layers
		(0 "F.Cu" signal "TOP")
		(4 "In1.Cu" signal "L2GND")
		(6 "In2.Cu" signal "L3")
		(8 "In3.Cu" signal "L4GND")
		(10 "In4.Cu" signal "L5")
		(12 "In5.Cu" signal "L6VCC")
		(14 "In6.Cu" signal "L7VCC")
		(16 "In7.Cu" signal "L8")
		(18 "In8.Cu" signal "L9GND")
		(20 "In9.Cu" signal "L10")
		(22 "In10.Cu" signal "L11GND")
		(2 "B.Cu" signal "BOTTOM")
		(9 "F.Adhes" user "F.Adhesive")
		(11 "B.Adhes" user "B.Adhesive")
		(13 "F.Paste" user "Package Geometry/Pastemask Top")
		(15 "B.Paste" user "Package Geometry/Pastemask Bottom")
		(5 "F.SilkS" user "Ref Des/Silkscreen Top")
		(7 "B.SilkS" user "Ref Des/Silkscreen Bottom")
		(1 "F.Mask" user "Board Geometry/Soldermask Top")
		(3 "B.Mask" user "Board Geometry/Soldermask Bottom")
		(17 "Dwgs.User" user "User.Drawings")
		(19 "Cmts.User" user "User.Comments")
		(21 "Eco1.User" user "User.Eco1")
		(23 "Eco2.User" user "User.Eco2")
		(25 "Edge.Cuts" user "Board Geometry/Outline")
		(27 "Margin" user)
		(31 "F.CrtYd" user "Package Geometry/Place Bound Top")
		(29 "B.CrtYd" user "Package Geometry/Place Bound Bottom")
		(35 "F.Fab" user "Ref Des/Assembly Top")
		(33 "B.Fab" user "Ref Des/Assembly Bottom")
	)
	(footprint ""
		(layer "F.Cu")
		(at 318.482218 -127.8001 180)
		(property "Reference" "Q245"
			(at 0 0 180)
			(layer "F.SilkS")
			(hide yes)
			(effects
				(font
					(size 1.27 1.27)
				)
			)
		)
		(property "Value" "2N7002K-2-GP"
			(at 0.127 -8.9662 180)
			(unlocked yes)
			(layer "F.Fab")
			(hide yes)
			(effects
				(font
					(size 1.016 1.016)
					(thickness 0.1524)
				)
			)
		)
		(property "Device Type" "SOT23DGS2D4H44"
			(at 0.127 -10.4902 180)
			(unlocked yes)
			(layer "F.Fab")
			(hide yes)
			(effects
				(font
					(size 1.016 1.016)
					(thickness 0.1524)
				)
			)
		)
		(duplicate_pad_numbers_are_jumpers no)
		(fp_line
			(start 1.651 1.778)
			(end 1.651 -1.778)
			(stroke
				(width 0.1524)
				(type default)
			)
			(layer "F.SilkS")
		)
		(fp_line
			(start 1.651 -1.778)
			(end -1.651 -1.778)
			(stroke
				(width 0.1524)
				(type default)
			)
			(layer "F.SilkS")
		)
		(fp_line
			(start -1.651 1.778)
			(end 1.651 1.778)
			(stroke
				(width 0.1524)
				(type default)
			)
			(layer "F.SilkS")
		)
		(fp_line
			(start -1.651 -1.778)
			(end -1.651 1.778)
			(stroke
				(width 0.1524)
				(type default)
			)
			(layer "F.SilkS")
		)
		(fp_poly
			(pts
				(xy -1.778 1.8796) (xy -1.778 -1.8796) (xy 1.778 -1.8796) (xy 1.778 1.8796)
			)
			(stroke
				(width 0)
				(type default)
			)
			(fill no)
			(layer "F.CrtYd")
		)
		(fp_poly
			(pts
				(xy -1.778 1.8796) (xy -1.778 -1.8796) (xy 1.778 -1.8796) (xy 1.778 1.8796)
			)
			(stroke
				(width 0)
				(type default)
			)
			(fill no)
			(layer "F.Fab")
		)
		(pad "D" smd custom
			(at 0 -0.9525 180)
			(size 0.1905 0.1905)
			(layers "F.Cu" "F.Mask" "F.Paste")
			(net "FLT_HDD018_N")
			(options
				(clearance outline)
				(anchor circle)
			)
			(primitives
				(gr_poly
					(pts
						(arc
							(start -0.1778 0.5715)
							(mid -0.321484 0.511984)
							(end -0.381 0.3683)
						)
						(arc
							(start -0.381 -0.3683)
							(mid -0.321484 -0.511984)
							(end -0.1778 -0.5715)
						)
						(arc
							(start 0.1778 -0.5715)
							(mid 0.321484 -0.511984)
							(end 0.381 -0.3683)
						)
						(arc
							(start 0.381 0.3683)
							(mid 0.321484 0.511984)
							(end 0.1778 0.5715)
						)
					)
					(width 0)
					(fill yes)
				)
			)
		)
		(pad "G" smd custom
			(at -0.98425 0.9525 180)
			(size 0.1905 0.1905)
			(layers "F.Cu" "F.Mask" "F.Paste")
			(net "DRIVE_A_18_FLT_LED")
			(options
				(clearance outline)
				(anchor circle)
			)
			(primitives
				(gr_poly
					(pts
						(arc
							(start -0.1778 0.5715)
							(mid -0.321484 0.511984)
							(end -0.381 0.3683)
						)
						(arc
							(start -0.381 -0.3683)
							(mid -0.321484 -0.511984)
							(end -0.1778 -0.5715)
						)
						(arc
							(start 0.1778 -0.5715)
							(mid 0.321484 -0.511984)
							(end 0.381 -0.3683)
						)
						(arc
							(start 0.381 0.3683)
							(mid 0.321484 0.511984)
							(end 0.1778 0.5715)
						)
					)
					(width 0)
					(fill yes)
				)
			)
		)
		(pad "S" smd custom
			(at 0.98425 0.9525 180)
			(size 0.1905 0.1905)
			(layers "F.Cu" "F.Mask" "F.Paste")
			(net "GND")
			(options
				(clearance outline)
				(anchor circle)
			)
			(primitives
				(gr_poly
					(pts
						(arc
							(start -0.1778 0.5715)
							(mid -0.321484 0.511984)
							(end -0.381 0.3683)
						)
						(arc
							(start -0.381 -0.3683)
							(mid -0.321484 -0.511984)
							(end -0.1778 -0.5715)
						)
						(arc
							(start 0.1778 -0.5715)
							(mid 0.321484 -0.511984)
							(end 0.381 -0.3683)
						)
						(arc
							(start 0.381 0.3683)
							(mid 0.321484 0.511984)
							(end 0.1778 0.5715)
						)
					)
					(width 0)
					(fill yes)
				)
			)
		)
	)
	(footprint ""
		(layer "F.Cu")
		(at 74.206862 -127.798068 180)
		(property "Reference" "Q277"
			(at 0 0 180)
			(layer "F.SilkS")
			(hide yes)
			(effects
				(font
					(size 1.27 1.27)
				)
			)
		)
		(property "Value" "SSM3K324R-GP"
			(at 0.127 -8.9662 180)
			(unlocked yes)
			(layer "F.Fab")
			(hide yes)
			(effects
				(font
					(size 1.016 1.016)
					(thickness 0.1524)
				)
			)
		)
		(property "Device Type" "SOT23DGS2D4H35"
			(at 0.127 -10.4902 180)
			(unlocked yes)
			(layer "F.Fab")
			(hide yes)
			(effects
				(font
					(size 1.016 1.016)
					(thickness 0.1524)
				)
			)
		)
		(duplicate_pad_numbers_are_jumpers no)
		(fp_line
			(start 1.651 1.778)
			(end 1.651 -1.778)
			(stroke
				(width 0.1524)
				(type default)
			)
			(layer "F.SilkS")
		)
		(fp_line
			(start 1.651 -1.778)
			(end -1.651 -1.778)
			(stroke
				(width 0.1524)
				(type default)
			)
			(layer "F.SilkS")
		)
		(fp_line
			(start -1.651 1.778)
			(end 1.651 1.778)
			(stroke
				(width 0.1524)
				(type default)
			)
			(layer "F.SilkS")
		)
		(fp_line
			(start -1.651 -1.778)
			(end -1.651 1.778)
			(stroke
				(width 0.1524)
				(type default)
			)
			(layer "F.SilkS")
		)
		(fp_poly
			(pts
				(xy -1.778 1.8796) (xy -1.778 -1.8796) (xy 1.778 -1.8796) (xy 1.778 1.8796)
			)
			(stroke
				(width 0)
				(type default)
			)
			(fill no)
			(layer "F.CrtYd")
		)
		(fp_poly
			(pts
				(xy -1.778 1.8796) (xy -1.778 -1.8796) (xy 1.778 -1.8796) (xy 1.778 1.8796)
			)
			(stroke
				(width 0)
				(type default)
			)
			(fill no)
			(layer "F.Fab")
		)
		(pad "D" smd custom
			(at 0 -0.9525 180)
			(size 0.1905 0.1905)
			(layers "F.Cu" "F.Mask" "F.Paste")
			(net "DRV_ACT_14_N")
			(options
				(clearance outline)
				(anchor circle)
			)
			(primitives
				(gr_poly
					(pts
						(arc
							(start -0.1778 0.5715)
							(mid -0.321484 0.511984)
							(end -0.381 0.3683)
						)
						(arc
							(start -0.381 -0.3683)
							(mid -0.321484 -0.511984)
							(end -0.1778 -0.5715)
						)
						(arc
							(start 0.1778 -0.5715)
							(mid 0.321484 -0.511984)
							(end 0.381 -0.3683)
						)
						(arc
							(start 0.381 0.3683)
							(mid 0.321484 0.511984)
							(end 0.1778 0.5715)
						)
					)
					(width 0)
					(fill yes)
				)
			)
		)
		(pad "G" smd custom
			(at -0.98425 0.9525 180)
			(size 0.1905 0.1905)
			(layers "F.Cu" "F.Mask" "F.Paste")
			(net "DRIVE_A_14_ACT")
			(options
				(clearance outline)
				(anchor circle)
			)
			(primitives
				(gr_poly
					(pts
						(arc
							(start -0.1778 0.5715)
							(mid -0.321484 0.511984)
							(end -0.381 0.3683)
						)
						(arc
							(start -0.381 -0.3683)
							(mid -0.321484 -0.511984)
							(end -0.1778 -0.5715)
						)
						(arc
							(start 0.1778 -0.5715)
							(mid 0.321484 -0.511984)
							(end 0.381 -0.3683)
						)
						(arc
							(start 0.381 0.3683)
							(mid 0.321484 0.511984)
							(end 0.1778 0.5715)
						)
					)
					(width 0)
					(fill yes)
				)
			)
		)
		(pad "S" smd custom
			(at 0.98425 0.9525 180)
			(size 0.1905 0.1905)
			(layers "F.Cu" "F.Mask" "F.Paste")
			(net "GND")
			(options
				(clearance outline)
				(anchor circle)
			)
			(primitives
				(gr_poly
					(pts
						(arc
							(start -0.1778 0.5715)
							(mid -0.321484 0.511984)
							(end -0.381 0.3683)
						)
						(arc
							(start -0.381 -0.3683)
							(mid -0.321484 -0.511984)
							(end -0.1778 -0.5715)
						)
						(arc
							(start 0.1778 -0.5715)
							(mid 0.321484 -0.511984)
							(end 0.381 -0.3683)
						)
						(arc
							(start 0.381 0.3683)
							(mid 0.321484 0.511984)
							(end 0.1778 0.5715)
						)
					)
					(width 0)
					(fill yes)
				)
			)
		)
	)
	(footprint ""
		(layer "F.Cu")
		(at 381.13716 -134.866126 180)
		(property "Reference" "Q10"
			(at 0 0 180)
			(layer "F.SilkS")
			(hide yes)
			(effects
				(font
					(size 1.27 1.27)
				)
			)
		)
		(property "Value" "MMBT3904TT1G-GP"
			(at 0 -9.7282 180)
			(unlocked yes)
			(layer "F.Fab")
			(hide yes)
			(effects
				(font
					(size 1.016 1.016)
					(thickness 0.1524)
				)
			)
		)
		(property "Device Type" "SC75CBE1D6H36"
			(at 0 -11.6332 180)
			(unlocked yes)
			(layer "F.Fab")
			(hide yes)
			(effects
				(font
					(size 1.016 1.016)
					(thickness 0.1524)
				)
			)
		)
		(duplicate_pad_numbers_are_jumpers no)
		(fp_line
			(start 0.9652 1.3716)
			(end 0.9652 -1.3716)
			(stroke
				(width 0.1524)
				(type default)
			)
			(layer "F.SilkS")
		)
		(fp_line
			(start 0.9652 -1.3716)
			(end -0.9652 -1.3716)
			(stroke
				(width 0.1524)
				(type default)
			)
			(layer "F.SilkS")
		)
		(fp_line
			(start -0.9652 1.3716)
			(end 0.9652 1.3716)
			(stroke
				(width 0.1524)
				(type default)
			)
			(layer "F.SilkS")
		)
		(fp_line
			(start -0.9652 -1.3716)
			(end -0.9652 1.3716)
			(stroke
				(width 0.1524)
				(type default)
			)
			(layer "F.SilkS")
		)
		(fp_rect
			(start -1.0414 1.4478)
			(end 1.0414 -1.4478)
			(stroke
				(width 0)
				(type default)
			)
			(fill no)
			(layer "F.CrtYd")
		)
		(fp_poly
			(pts
				(xy -1.0414 -1.4478) (xy 1.0414 -1.4478) (xy 1.0414 1.4478) (xy -1.0414 1.4478)
			)
			(stroke
				(width 0)
				(type default)
			)
			(fill no)
			(layer "F.Fab")
		)
		(pad "B" smd custom
			(at -0.508 0.7112 180)
			(size 0.127 0.127)
			(layers "F.Cu" "F.Mask" "F.Paste")
			(net "VCCP_B")
			(options
				(clearance outline)
				(anchor circle)
			)
			(primitives
				(gr_poly
					(pts
						(arc
							(start -0.044958 0.4572)
							(mid -0.192463 0.399794)
							(end -0.254 0.254)
						)
						(xy -0.254 -0.254)
						(arc
							(start -0.253746 -0.254)
							(mid -0.192968 -0.398936)
							(end -0.04699 -0.4572)
						)
						(arc
							(start 0.04699 -0.4572)
							(mid 0.192989 -0.398958)
							(end 0.253746 -0.254)
						)
						(xy 0.254 -0.254)
						(arc
							(start 0.254 0.254)
							(mid 0.192404 0.399734)
							(end 0.044958 0.4572)
						)
					)
					(width 0)
					(fill yes)
				)
			)
		)
		(pad "C" smd custom
			(at 0 -0.7112 180)
			(size 0.127 0.127)
			(layers "F.Cu" "F.Mask" "F.Paste")
			(net "P12V_B")
			(options
				(clearance outline)
				(anchor circle)
			)
			(primitives
				(gr_poly
					(pts
						(arc
							(start -0.044958 0.4572)
							(mid -0.192463 0.399794)
							(end -0.254 0.254)
						)
						(xy -0.254 -0.254)
						(arc
							(start -0.253746 -0.254)
							(mid -0.192968 -0.398936)
							(end -0.04699 -0.4572)
						)
						(arc
							(start 0.04699 -0.4572)
							(mid 0.192989 -0.398958)
							(end 0.253746 -0.254)
						)
						(xy 0.254 -0.254)
						(arc
							(start 0.254 0.254)
							(mid 0.192404 0.399734)
							(end 0.044958 0.4572)
						)
					)
					(width 0)
					(fill yes)
				)
			)
		)
		(pad "E" smd custom
			(at 0.508 0.7112 180)
			(size 0.127 0.127)
			(layers "F.Cu" "F.Mask" "F.Paste")
			(net "P3V3_B_BIAS")
			(options
				(clearance outline)
				(anchor circle)
			)
			(primitives
				(gr_poly
					(pts
						(arc
							(start -0.044958 0.4572)
							(mid -0.192463 0.399794)
							(end -0.254 0.254)
						)
						(xy -0.254 -0.254)
						(arc
							(start -0.253746 -0.254)
							(mid -0.192968 -0.398936)
							(end -0.04699 -0.4572)
						)
						(arc
							(start 0.04699 -0.4572)
							(mid 0.192989 -0.398958)
							(end 0.253746 -0.254)
						)
						(xy 0.254 -0.254)
						(arc
							(start 0.254 0.254)
							(mid 0.192404 0.399734)
							(end 0.044958 0.4572)
						)
					)
					(width 0)
					(fill yes)
				)
			)
		)
	)
	(footprint ""
		(layer "F.Cu")
		(at 398.88795 -272.585942 180)
		(property "Reference" "R325"
			(at 0 0 180)
			(layer "F.SilkS")
			(hide yes)
			(effects
				(font
					(size 1.27 1.27)
				)
			)
		)
		(property "Value" "0R2J-2-GP"
			(at 0.064008 -3.993896 180)
			(unlocked yes)
			(layer "F.Fab")
			(hide yes)
			(effects
				(font
					(size 1.016 1.016)
					(thickness 0.1524)
				)
			)
		)
		(property "Device Type" "R402H16"
			(at 0.064008 -5.517896 180)
			(unlocked yes)
			(layer "F.Fab")
			(hide yes)
			(effects
				(font
					(size 1.016 1.016)
					(thickness 0.1524)
				)
			)
		)
		(duplicate_pad_numbers_are_jumpers no)
		(fp_line
			(start 0.508 -0.9398)
			(end -0.508 -0.9398)
			(stroke
				(width 0.1524)
				(type default)
			)
			(layer "F.SilkS")
		)
		(fp_line
			(start -0.508 -0.9398)
			(end -0.508 0.9398)
			(stroke
				(width 0.1524)
				(type default)
			)
			(layer "F.SilkS")
		)
		(fp_rect
			(start -0.508 0.9398)
			(end 0.508 -0.9398)
			(stroke
				(width 0)
				(type default)
			)
			(fill no)
			(layer "F.CrtYd")
		)
		(fp_rect
			(start -0.508 0.9398)
			(end 0.508 -0.9398)
			(stroke
				(width 0)
				(type default)
			)
			(fill no)
			(layer "F.Fab")
		)
		(pad "1" smd custom
			(at 0 -0.4445 180)
			(size 0.1397 0.1397)
			(layers "F.Cu" "F.Mask" "F.Paste")
			(net "DRIVE_A_8_PWR")
			(options
				(clearance outline)
				(anchor circle)
			)
			(primitives
				(gr_poly
					(pts
						(arc
							(start -0.1778 -0.2794)
							(mid -0.249642 -0.249642)
							(end -0.2794 -0.1778)
						)
						(arc
							(start -0.2794 0.1778)
							(mid -0.249642 0.249642)
							(end -0.1778 0.2794)
						)
						(arc
							(start 0.1778 0.2794)
							(mid 0.249642 0.249642)
							(end 0.2794 0.1778)
						)
						(arc
							(start 0.2794 -0.1778)
							(mid 0.249642 -0.249642)
							(end 0.1778 -0.2794)
						)
					)
					(width 0)
					(fill yes)
				)
			)
		)
		(pad "2" smd custom
			(at 0 0.4445 180)
			(size 0.1397 0.1397)
			(layers "F.Cu" "F.Mask" "F.Paste")
			(net "SW_PWR_R_HDD8")
			(options
				(clearance outline)
				(anchor circle)
			)
			(primitives
				(gr_poly
					(pts
						(arc
							(start -0.1778 -0.2794)
							(mid -0.249642 -0.249642)
							(end -0.2794 -0.1778)
						)
						(arc
							(start -0.2794 0.1778)
							(mid -0.249642 0.249642)
							(end -0.1778 0.2794)
						)
						(arc
							(start 0.1778 0.2794)
							(mid 0.249642 0.249642)
							(end 0.2794 0.1778)
						)
						(arc
							(start 0.2794 -0.1778)
							(mid 0.249642 -0.249642)
							(end 0.1778 -0.2794)
						)
					)
					(width 0)
					(fill yes)
				)
			)
		)
	)
	(footprint ""
		(layer "F.Cu")
		(at 23.732998 -292.270942)
		(property "Reference" "R957"
			(at 0 0 0)
			(layer "F.SilkS")
			(hide yes)
			(effects
				(font
					(size 1.27 1.27)
				)
			)
		)
		(property "Value" "2R6F-GP"
			(at -0.0508 -4.8514 0)
			(unlocked yes)
			(layer "F.Fab")
			(hide yes)
			(effects
				(font
					(size 1.016 1.016)
					(thickness 0.1524)
				)
			)
		)
		(property "Device Type" "R1206H26"
			(at 0 -6.3754 0)
			(unlocked yes)
			(layer "F.Fab")
			(hide yes)
			(effects
				(font
					(size 1.016 1.016)
					(thickness 0.1524)
				)
			)
		)
		(duplicate_pad_numbers_are_jumpers no)
		(fp_line
			(start -1.016 -2.2352)
			(end 1.016 -2.2352)
			(stroke
				(width 0.1524)
				(type default)
			)
			(layer "F.SilkS")
		)
		(fp_line
			(start -1.016 2.2352)
			(end -1.016 -2.2352)
			(stroke
				(width 0.1524)
				(type default)
			)
			(layer "F.SilkS")
		)
		(fp_line
			(start 1.016 -2.2352)
			(end 1.016 2.2352)
			(stroke
				(width 0.1524)
				(type default)
			)
			(layer "F.SilkS")
		)
		(fp_line
			(start 1.016 2.2352)
			(end -1.016 2.2352)
			(stroke
				(width 0.1524)
				(type default)
			)
			(layer "F.SilkS")
		)
		(fp_rect
			(start -1.0922 2.3114)
			(end 1.0922 -2.3114)
			(stroke
				(width 0)
				(type default)
			)
			(fill no)
			(layer "F.CrtYd")
		)
		(fp_poly
			(pts
				(xy -1.0922 -2.3114) (xy 1.0922 -2.3114) (xy 1.0922 2.3114) (xy -1.0922 2.3114)
			)
			(stroke
				(width 0)
				(type default)
			)
			(fill no)
			(layer "F.Fab")
		)
		(pad "1" smd rect
			(at 0 -1.397)
			(size 1.651 1.27)
			(layers "F.Cu" "F.Mask" "F.Paste")
			(net "P5V_HDD0")
		)
		(pad "2" smd rect
			(at 0 1.397)
			(size 1.651 1.27)
			(layers "F.Cu" "F.Mask" "F.Paste")
			(net "5V_PRE_0")
		)
	)
	(footprint ""
		(layer "F.Cu")
		(at 409.144978 -242.25377)
		(property "Reference" "R263"
			(at 0 0 0)
			(layer "F.SilkS")
			(hide yes)
			(effects
				(font
					(size 1.27 1.27)
				)
			)
		)
		(property "Value" "130R3F-GP"
			(at -0.0254 -2.5146 0)
			(unlocked yes)
			(layer "F.Fab")
			(hide yes)
			(effects
				(font
					(size 1.016 1.016)
					(thickness 0.1524)
				)
			)
		)
		(property "Device Type" "R603H22"
			(at -0.0254 -4.0386 0)
			(unlocked yes)
			(layer "F.Fab")
			(hide yes)
			(effects
				(font
					(size 1.016 1.016)
					(thickness 0.1524)
				)
			)
		)
		(duplicate_pad_numbers_are_jumpers no)
		(fp_line
			(start -0.4826 0)
			(end -0.2032 0)
			(stroke
				(width 0.2032)
				(type default)
			)
			(layer "F.SilkS")
		)
		(fp_line
			(start 0.2032 0)
			(end 0.4826 0)
			(stroke
				(width 0.2032)
				(type default)
			)
			(layer "F.SilkS")
		)
		(fp_rect
			(start -0.5842 1.3335)
			(end 0.5842 -1.3335)
			(stroke
				(width 0)
				(type default)
			)
			(fill no)
			(layer "F.CrtYd")
		)
		(fp_rect
			(start -0.5842 1.3335)
			(end 0.5842 -1.3335)
			(stroke
				(width 0)
				(type default)
			)
			(fill no)
			(layer "F.Fab")
		)
		(pad "1" smd custom
			(at 0 -0.762)
			(size 0.2159 0.2159)
			(layers "F.Cu" "F.Mask" "F.Paste")
			(net "P5V_A_3")
			(options
				(clearance outline)
				(anchor circle)
			)
			(primitives
				(gr_poly
					(pts
						(arc
							(start -0.3302 -0.4318)
							(mid -0.402042 -0.402042)
							(end -0.4318 -0.3302)
						)
						(arc
							(start -0.4318 0.3302)
							(mid -0.402042 0.402042)
							(end -0.3302 0.4318)
						)
						(arc
							(start 0.3302 0.4318)
							(mid 0.402042 0.402042)
							(end 0.4318 0.3302)
						)
						(arc
							(start 0.4318 -0.3302)
							(mid 0.402042 -0.402042)
							(end 0.3302 -0.4318)
						)
					)
					(width 0)
					(fill yes)
				)
			)
		)
		(pad "2" smd custom
			(at 0 0.762)
			(size 0.2159 0.2159)
			(layers "F.Cu" "F.Mask" "F.Paste")
			(net "FLT_HDD9")
			(options
				(clearance outline)
				(anchor circle)
			)
			(primitives
				(gr_poly
					(pts
						(arc
							(start -0.3302 -0.4318)
							(mid -0.402042 -0.402042)
							(end -0.4318 -0.3302)
						)
						(arc
							(start -0.4318 0.3302)
							(mid -0.402042 0.402042)
							(end -0.3302 0.4318)
						)
						(arc
							(start 0.3302 0.4318)
							(mid 0.402042 0.402042)
							(end 0.4318 0.3302)
						)
						(arc
							(start 0.4318 -0.3302)
							(mid 0.402042 -0.402042)
							(end 0.3302 -0.4318)
						)
					)
					(width 0)
					(fill yes)
				)
			)
		)
	)
)
